# SCM (Grand Teton) — schematic netlist excerpt (pin names and nets, part order shuffled) for the footprints in the layout excerpt that follows; sources: Cadence DE-HDL packaged netlist, KiCad conversion of 12092022_DA0F0TMDCD0_F0T_Management_Board_D_brd_V3_OCP.brd

R299  Q_RES  4.7K 1% CHIP  pkg 0402LF  page 28 : A = P3V3_AUX ; B = SMB_DEBUG_AUX_LVC3_USB_R1_SDA
R295  Q_RES  10K 1% CHIP  pkg 0402LF  page 28 : A = P3V3_AUX ; B = DEBUG_PORT_PRSNT_BUF_R_EN

(kicad_pcb
	(version 20260206)
	(generator "pcbnew")
	(generator_version "10.0")
	(general
		(thickness 1.6)
		(legacy_teardrops no)
	)
	(paper "A4")
	(title_block
		(title "12092022_DA0F0TMDCD0_F0T_Management_Board_D_brd_V3_OCP.brd")
		(comment 1 "Grand Teton / footprints 883-884 of 1440")
	)
	(layers
		(0 "F.Cu" signal "TOP")
		(4 "In1.Cu" signal "GND")
		(6 "In2.Cu" signal "IN1")
		(8 "In3.Cu" signal "GND1")
		(10 "In4.Cu" signal "IN2")
		(12 "In5.Cu" signal "VCC")
		(14 "In6.Cu" signal "VCC1")
		(16 "In7.Cu" signal "IN3")
		(18 "In8.Cu" signal "GND2")
		(20 "In9.Cu" signal "IN4")
		(22 "In10.Cu" signal "GND3")
		(2 "B.Cu" signal "BOTTOM")
		(9 "F.Adhes" user "F.Adhesive")
		(11 "B.Adhes" user "B.Adhesive")
		(13 "F.Paste" user "Package Geometry/Pastemask Top")
		(15 "B.Paste" user "Package Geometry/Pastemask Bottom")
		(5 "F.SilkS" user "Ref Des/Silkscreen Top")
		(7 "B.SilkS" user "Ref Des/Silkscreen Bottom")
		(1 "F.Mask" user "Board Geometry/Soldermask Top")
		(3 "B.Mask" user "Board Geometry/Soldermask Bottom")
		(17 "Dwgs.User" user "User.Drawings")
		(19 "Cmts.User" user "User.Comments")
		(21 "Eco1.User" user "User.Eco1")
		(23 "Eco2.User" user "User.Eco2")
		(25 "Edge.Cuts" user "Board Geometry/Outline")
		(27 "Margin" user)
		(31 "F.CrtYd" user "Package Geometry/Place Bound Top")
		(29 "B.CrtYd" user "Package Geometry/Place Bound Bottom")
		(35 "F.Fab" user "Ref Des/Assembly Top")
		(33 "B.Fab" user "Ref Des/Assembly Bottom")
	)
	(footprint ""
		(layer "B.Cu")
		(at 46.21784 -24.1173 90)
		(property "Reference" "R295"
			(at 0 0 90)
			(layer "B.SilkS")
			(hide yes)
			(effects
				(font
					(size 1.27 1.27)
				)
				(justify mirror)
			)
		)
		(property "Value" ""
			(at 0 0 90)
			(layer "B.Fab")
			(effects
				(font
					(size 1.27 1.27)
				)
				(justify mirror)
			)
		)
		(duplicate_pad_numbers_are_jumpers no)
		(fp_line
			(start 0.7874 -0.4064)
			(end -0.7874 -0.4064)
			(stroke
				(width 0.1524)
				(type default)
			)
			(layer "B.SilkS")
		)
		(fp_line
			(start -0.7874 -0.4064)
			(end -0.7874 0.4064)
			(stroke
				(width 0.1524)
				(type default)
			)
			(layer "B.SilkS")
		)
		(fp_line
			(start 0.7874 0.4064)
			(end 0.7874 -0.4064)
			(stroke
				(width 0.1524)
				(type default)
			)
			(layer "B.SilkS")
		)
		(fp_line
			(start -0.7874 0.4064)
			(end 0.7874 0.4064)
			(stroke
				(width 0.1524)
				(type default)
			)
			(layer "B.SilkS")
		)
		(fp_line
			(start 0.67945 -0.305054)
			(end 0.12065 -0.305054)
			(stroke
				(width 0.1)
				(type default)
			)
			(layer "B.Fab")
		)
		(fp_line
			(start 0.12065 -0.305054)
			(end 0.12065 -0.2794)
			(stroke
				(width 0.1)
				(type default)
			)
			(layer "B.Fab")
		)
		(fp_line
			(start -0.12065 -0.3048)
			(end -0.67945 -0.3048)
			(stroke
				(width 0.1)
				(type default)
			)
			(layer "B.Fab")
		)
		(fp_line
			(start -0.67945 -0.3048)
			(end -0.67945 0.3048)
			(stroke
				(width 0.1)
				(type default)
			)
			(layer "B.Fab")
		)
		(fp_line
			(start 0.12065 -0.2794)
			(end -0.12065 -0.2794)
			(stroke
				(width 0.1)
				(type default)
			)
			(layer "B.Fab")
		)
		(fp_line
			(start -0.12065 -0.2794)
			(end -0.12065 -0.3048)
			(stroke
				(width 0.1)
				(type default)
			)
			(layer "B.Fab")
		)
		(fp_line
			(start 0.12065 0.2794)
			(end 0.12065 0.3048)
			(stroke
				(width 0.1)
				(type default)
			)
			(layer "B.Fab")
		)
		(fp_line
			(start -0.120396 0.2794)
			(end 0.12065 0.2794)
			(stroke
				(width 0.1)
				(type default)
			)
			(layer "B.Fab")
		)
		(fp_line
			(start 0.67945 0.3048)
			(end 0.67945 -0.305054)
			(stroke
				(width 0.1)
				(type default)
			)
			(layer "B.Fab")
		)
		(fp_line
			(start 0.12065 0.3048)
			(end 0.67945 0.3048)
			(stroke
				(width 0.1)
				(type default)
			)
			(layer "B.Fab")
		)
		(fp_line
			(start -0.120396 0.3048)
			(end -0.120396 0.2794)
			(stroke
				(width 0.1)
				(type default)
			)
			(layer "B.Fab")
		)
		(fp_line
			(start -0.67945 0.3048)
			(end -0.120396 0.3048)
			(stroke
				(width 0.1)
				(type default)
			)
			(layer "B.Fab")
		)
		(pad "1" smd circle
			(at 0.40005 0 270)
			(size 0 0)
			(layers "B.Cu" "B.Mask" "B.Paste")
			(net "P3V3_AUX")
		)
		(pad "2" smd circle
			(at -0.40005 0 270)
			(size 0 0)
			(layers "B.Cu" "B.Mask" "B.Paste")
			(net "DEBUG_PORT_PRSNT_BUF_R_EN")
		)
	)
	(footprint ""
		(layer "B.Cu")
		(at 16.764 -70.104 90)
		(property "Reference" "R299"
			(at 0 0 90)
			(layer "B.SilkS")
			(hide yes)
			(effects
				(font
					(size 1.27 1.27)
				)
				(justify mirror)
			)
		)
		(property "Value" ""
			(at 0 0 90)
			(layer "B.Fab")
			(effects
				(font
					(size 1.27 1.27)
				)
				(justify mirror)
			)
		)
		(duplicate_pad_numbers_are_jumpers no)
		(fp_line
			(start 0.7874 -0.4064)
			(end -0.7874 -0.4064)
			(stroke
				(width 0.1524)
				(type default)
			)
			(layer "B.SilkS")
		)
		(fp_line
			(start -0.7874 -0.4064)
			(end -0.7874 0.4064)
			(stroke
				(width 0.1524)
				(type default)
			)
			(layer "B.SilkS")
		)
		(fp_line
			(start 0.7874 0.4064)
			(end 0.7874 -0.4064)
			(stroke
				(width 0.1524)
				(type default)
			)
			(layer "B.SilkS")
		)
		(fp_line
			(start -0.7874 0.4064)
			(end 0.7874 0.4064)
			(stroke
				(width 0.1524)
				(type default)
			)
			(layer "B.SilkS")
		)
		(fp_line
			(start 0.67945 -0.305054)
			(end 0.12065 -0.305054)
			(stroke
				(width 0.1)
				(type default)
			)
			(layer "B.Fab")
		)
		(fp_line
			(start 0.12065 -0.305054)
			(end 0.12065 -0.2794)
			(stroke
				(width 0.1)
				(type default)
			)
			(layer "B.Fab")
		)
		(fp_line
			(start -0.12065 -0.3048)
			(end -0.67945 -0.3048)
			(stroke
				(width 0.1)
				(type default)
			)
			(layer "B.Fab")
		)
		(fp_line
			(start -0.67945 -0.3048)
			(end -0.67945 0.3048)
			(stroke
				(width 0.1)
				(type default)
			)
			(layer "B.Fab")
		)
		(fp_line
			(start 0.12065 -0.2794)
			(end -0.12065 -0.2794)
			(stroke
				(width 0.1)
				(type default)
			)
			(layer "B.Fab")
		)
		(fp_line
			(start -0.12065 -0.2794)
			(end -0.12065 -0.3048)
			(stroke
				(width 0.1)
				(type default)
			)
			(layer "B.Fab")
		)
		(fp_line
			(start 0.12065 0.2794)
			(end 0.12065 0.3048)
			(stroke
				(width 0.1)
				(type default)
			)
			(layer "B.Fab")
		)
		(fp_line
			(start -0.120396 0.2794)
			(end 0.12065 0.2794)
			(stroke
				(width 0.1)
				(type default)
			)
			(layer "B.Fab")
		)
		(fp_line
			(start 0.67945 0.3048)
			(end 0.67945 -0.305054)
			(stroke
				(width 0.1)
				(type default)
			)
			(layer "B.Fab")
		)
		(fp_line
			(start 0.12065 0.3048)
			(end 0.67945 0.3048)
			(stroke
				(width 0.1)
				(type default)
			)
			(layer "B.Fab")
		)
		(fp_line
			(start -0.120396 0.3048)
			(end -0.120396 0.2794)
			(stroke
				(width 0.1)
				(type default)
			)
			(layer "B.Fab")
		)
		(fp_line
			(start -0.67945 0.3048)
			(end -0.120396 0.3048)
			(stroke
				(width 0.1)
				(type default)
			)
			(layer "B.Fab")
		)
		(pad "1" smd circle
			(at 0.40005 0 270)
			(size 0 0)
			(layers "B.Cu" "B.Mask" "B.Paste")
			(net "P3V3_AUX")
		)
		(pad "2" smd circle
			(at -0.40005 0 270)
			(size 0 0)
			(layers "B.Cu" "B.Mask" "B.Paste")
			(net "SMB_DEBUG_AUX_LVC3_USB_R1_SDA")
		)
	)
)
